# T6G (Grand Teton) — schematic netlist excerpt (pin names and nets, part order shuffled) for the footprints in the layout excerpt that follows; sources: Cadence DE-HDL packaged netlist, KiCad conversion of 04192023_DAF0TMB3IC0_F0TG_MB_C_brd_V02_OCP.brd

PC481_1  Q_CAP  1UF 25V 10% X6S  pkg C0402  page 194 : A = SW_P12V_AUX_PVDDCR_CPU0_P0_FLT ; B = GND
PR486  Q_RES  1.5 1% EMPTY  pkg 0402LF  page 211 : A = SW_PVDDCR_CPU0_P1_SW2_RC ; B = GND

(kicad_pcb
	(version 20260206)
	(generator "pcbnew")
	(generator_version "10.0")
	(general
		(thickness 1.6)
		(legacy_teardrops no)
	)
	(paper "A4")
	(title_block
		(title "04192023_DAF0TMB3IC0_F0TG_MB_C_brd_V02_OCP.brd")
		(comment 1 "Grand Teton / footprints 1923-1924 of 8354")
	)
	(layers
		(0 "F.Cu" signal "TOP")
		(4 "In1.Cu" signal "GND")
		(6 "In2.Cu" signal "IN1")
		(8 "In3.Cu" signal "GND1")
		(10 "In4.Cu" signal "IN2")
		(12 "In5.Cu" signal "GND2")
		(14 "In6.Cu" signal "IN3")
		(16 "In7.Cu" signal "GND3")
		(18 "In8.Cu" signal "VCC")
		(20 "In9.Cu" signal "VCC1")
		(22 "In10.Cu" signal "GND4")
		(24 "In11.Cu" signal "IN4")
		(26 "In12.Cu" signal "GND5")
		(28 "In13.Cu" signal "IN5")
		(30 "In14.Cu" signal "GND6")
		(32 "In15.Cu" signal "IN6")
		(34 "In16.Cu" signal "GND7")
		(2 "B.Cu" signal "BOTTOM")
		(9 "F.Adhes" user "F.Adhesive")
		(11 "B.Adhes" user "B.Adhesive")
		(13 "F.Paste" user "Package Geometry/Pastemask Top")
		(15 "B.Paste" user "Package Geometry/Pastemask Bottom")
		(5 "F.SilkS" user "Ref Des/Silkscreen Top")
		(7 "B.SilkS" user "Ref Des/Silkscreen Bottom")
		(1 "F.Mask" user "Board Geometry/Soldermask Top")
		(3 "B.Mask" user "Board Geometry/Soldermask Bottom")
		(17 "Dwgs.User" user "User.Drawings")
		(19 "Cmts.User" user "User.Comments")
		(21 "Eco1.User" user "User.Eco1")
		(23 "Eco2.User" user "User.Eco2")
		(25 "Edge.Cuts" user "Board Geometry/Outline")
		(27 "Margin" user)
		(31 "F.CrtYd" user "Package Geometry/Place Bound Top")
		(29 "B.CrtYd" user "Package Geometry/Place Bound Bottom")
		(35 "F.Fab" user "Ref Des/Assembly Top")
		(33 "B.Fab" user "Ref Des/Assembly Bottom")
	)
	(footprint ""
		(layer "F.Cu")
		(at 94.358968 -184.410096 -90)
		(property "Reference" "PR486"
			(at 0 0 270)
			(layer "F.SilkS")
			(hide yes)
			(effects
				(font
					(size 1.27 1.27)
				)
			)
		)
		(property "Value" ""
			(at 0 0 270)
			(layer "F.Fab")
			(effects
				(font
					(size 1.27 1.27)
				)
			)
		)
		(duplicate_pad_numbers_are_jumpers no)
		(fp_line
			(start -0.7874 0.4064)
			(end -0.7874 -0.4064)
			(stroke
				(width 0.1524)
				(type default)
			)
			(layer "F.SilkS")
		)
		(fp_line
			(start 0.7874 0.4064)
			(end -0.7874 0.4064)
			(stroke
				(width 0.1524)
				(type default)
			)
			(layer "F.SilkS")
		)
		(fp_line
			(start -0.7874 -0.4064)
			(end 0.7874 -0.4064)
			(stroke
				(width 0.1524)
				(type default)
			)
			(layer "F.SilkS")
		)
		(fp_line
			(start 0.7874 -0.4064)
			(end 0.7874 0.4064)
			(stroke
				(width 0.1524)
				(type default)
			)
			(layer "F.SilkS")
		)
		(fp_line
			(start -0.67945 0.3048)
			(end -0.67945 -0.305054)
			(stroke
				(width 0.1)
				(type default)
			)
			(layer "F.Fab")
		)
		(fp_line
			(start -0.12065 0.3048)
			(end -0.67945 0.3048)
			(stroke
				(width 0.1)
				(type default)
			)
			(layer "F.Fab")
		)
		(fp_line
			(start 0.120396 0.3048)
			(end 0.120396 0.2794)
			(stroke
				(width 0.1)
				(type default)
			)
			(layer "F.Fab")
		)
		(fp_line
			(start 0.67945 0.3048)
			(end 0.120396 0.3048)
			(stroke
				(width 0.1)
				(type default)
			)
			(layer "F.Fab")
		)
		(fp_line
			(start -0.12065 0.2794)
			(end -0.12065 0.3048)
			(stroke
				(width 0.1)
				(type default)
			)
			(layer "F.Fab")
		)
		(fp_line
			(start 0.120396 0.2794)
			(end -0.12065 0.2794)
			(stroke
				(width 0.1)
				(type default)
			)
			(layer "F.Fab")
		)
		(fp_line
			(start -0.12065 -0.2794)
			(end 0.12065 -0.2794)
			(stroke
				(width 0.1)
				(type default)
			)
			(layer "F.Fab")
		)
		(fp_line
			(start 0.12065 -0.2794)
			(end 0.12065 -0.3048)
			(stroke
				(width 0.1)
				(type default)
			)
			(layer "F.Fab")
		)
		(fp_line
			(start 0.12065 -0.3048)
			(end 0.67945 -0.3048)
			(stroke
				(width 0.1)
				(type default)
			)
			(layer "F.Fab")
		)
		(fp_line
			(start 0.67945 -0.3048)
			(end 0.67945 0.3048)
			(stroke
				(width 0.1)
				(type default)
			)
			(layer "F.Fab")
		)
		(fp_line
			(start -0.67945 -0.305054)
			(end -0.12065 -0.305054)
			(stroke
				(width 0.1)
				(type default)
			)
			(layer "F.Fab")
		)
		(fp_line
			(start -0.12065 -0.305054)
			(end -0.12065 -0.2794)
			(stroke
				(width 0.1)
				(type default)
			)
			(layer "F.Fab")
		)
		(pad "1" smd circle
			(at -0.40005 0 270)
			(size 0 0)
			(layers "F.Cu" "F.Mask" "F.Paste")
			(net "SW_PVDDCR_CPU0_P1_SW2_RC")
		)
		(pad "2" smd circle
			(at 0.40005 0 270)
			(size 0 0)
			(layers "F.Cu" "F.Mask" "F.Paste")
			(net "GND")
		)
	)
	(footprint ""
		(layer "F.Cu")
		(at 360.681778 -177.604674 90)
		(property "Reference" "PC481_1"
			(at 0 0 90)
			(layer "F.SilkS")
			(hide yes)
			(effects
				(font
					(size 1.27 1.27)
				)
			)
		)
		(property "Value" ""
			(at 0 0 90)
			(layer "F.Fab")
			(effects
				(font
					(size 1.27 1.27)
				)
			)
		)
		(duplicate_pad_numbers_are_jumpers no)
		(fp_line
			(start 0.7874 -0.4064)
			(end 0.7874 0.4064)
			(stroke
				(width 0.1524)
				(type default)
			)
			(layer "F.SilkS")
		)
		(fp_line
			(start -0.7874 -0.4064)
			(end 0.7874 -0.4064)
			(stroke
				(width 0.1524)
				(type default)
			)
			(layer "F.SilkS")
		)
		(fp_line
			(start 0.7874 0.4064)
			(end -0.7874 0.4064)
			(stroke
				(width 0.1524)
				(type default)
			)
			(layer "F.SilkS")
		)
		(fp_line
			(start -0.7874 0.4064)
			(end -0.7874 -0.4064)
			(stroke
				(width 0.1524)
				(type default)
			)
			(layer "F.SilkS")
		)
		(fp_line
			(start -0.12065 -0.305054)
			(end -0.12065 -0.2794)
			(stroke
				(width 0.1)
				(type default)
			)
			(layer "F.Fab")
		)
		(fp_line
			(start -0.67945 -0.305054)
			(end -0.12065 -0.305054)
			(stroke
				(width 0.1)
				(type default)
			)
			(layer "F.Fab")
		)
		(fp_line
			(start 0.67945 -0.3048)
			(end 0.67945 0.3048)
			(stroke
				(width 0.1)
				(type default)
			)
			(layer "F.Fab")
		)
		(fp_line
			(start 0.12065 -0.3048)
			(end 0.67945 -0.3048)
			(stroke
				(width 0.1)
				(type default)
			)
			(layer "F.Fab")
		)
		(fp_line
			(start 0.12065 -0.2794)
			(end 0.12065 -0.3048)
			(stroke
				(width 0.1)
				(type default)
			)
			(layer "F.Fab")
		)
		(fp_line
			(start -0.12065 -0.2794)
			(end 0.12065 -0.2794)
			(stroke
				(width 0.1)
				(type default)
			)
			(layer "F.Fab")
		)
		(fp_line
			(start 0.120396 0.2794)
			(end -0.12065 0.2794)
			(stroke
				(width 0.1)
				(type default)
			)
			(layer "F.Fab")
		)
		(fp_line
			(start -0.12065 0.2794)
			(end -0.12065 0.3048)
			(stroke
				(width 0.1)
				(type default)
			)
			(layer "F.Fab")
		)
		(fp_line
			(start 0.67945 0.3048)
			(end 0.120396 0.3048)
			(stroke
				(width 0.1)
				(type default)
			)
			(layer "F.Fab")
		)
		(fp_line
			(start 0.120396 0.3048)
			(end 0.120396 0.2794)
			(stroke
				(width 0.1)
				(type default)
			)
			(layer "F.Fab")
		)
		(fp_line
			(start -0.12065 0.3048)
			(end -0.67945 0.3048)
			(stroke
				(width 0.1)
				(type default)
			)
			(layer "F.Fab")
		)
		(fp_line
			(start -0.67945 0.3048)
			(end -0.67945 -0.305054)
			(stroke
				(width 0.1)
				(type default)
			)
			(layer "F.Fab")
		)
		(pad "1" smd circle
			(at -0.40005 0 90)
			(size 0 0)
			(layers "F.Cu" "F.Mask" "F.Paste")
			(net "SW_P12V_AUX_PVDDCR_CPU0_P0_FLT")
		)
		(pad "2" smd circle
			(at 0.40005 0 90)
			(size 0 0)
			(layers "F.Cu" "F.Mask" "F.Paste")
			(net "GND")
		)
	)
)
